# S9S_MB_2U (Grand Teton) — schematic netlist excerpt (pin names and nets, part order shuffled) for the footprints in the layout excerpt that follows; sources: Cadence DE-HDL packaged netlist, KiCad conversion of 03242023_DA0F0TMBIJ0_F0T_Motherboard_J_brd_V01_OCP.brd

C355  Q_CAP  47UF 4V 20% X6S  pkg C0805  page 75 : A = PVCCIN_CPU0 ; B = GND
R2420  Q_RES  33.2 1% CHIP  pkg 0402LF  page 240 : A = SMB_HOST_3V3AUX_SDA ; B = SMB_HOST_3V3AUX_SDA_R0
C447  Q_CAP  47UF 4V 20% X6S  pkg C0805  page 78 : A = PVCCD_HV_CPU1 ; B = GND

(kicad_pcb
	(version 20260206)
	(generator "pcbnew")
	(generator_version "10.0")
	(general
		(thickness 1.6)
		(legacy_teardrops no)
	)
	(paper "A4")
	(title_block
		(title "03242023_DA0F0TMBIJ0_F0T_Motherboard_J_brd_V01_OCP.brd")
		(comment 1 "Grand Teton / footprints 5311-5313 of 6105")
	)
	(layers
		(0 "F.Cu" signal "TOP")
		(4 "In1.Cu" signal "GND")
		(6 "In2.Cu" signal "IN1")
		(8 "In3.Cu" signal "GND1")
		(10 "In4.Cu" signal "IN2")
		(12 "In5.Cu" signal "GND2")
		(14 "In6.Cu" signal "IN3")
		(16 "In7.Cu" signal "GND3")
		(18 "In8.Cu" signal "VCC")
		(20 "In9.Cu" signal "VCC1")
		(22 "In10.Cu" signal "GND4")
		(24 "In11.Cu" signal "IN4")
		(26 "In12.Cu" signal "GND5")
		(28 "In13.Cu" signal "IN5")
		(30 "In14.Cu" signal "GND6")
		(32 "In15.Cu" signal "IN6")
		(34 "In16.Cu" signal "GND7")
		(2 "B.Cu" signal "BOTTOM")
		(9 "F.Adhes" user "F.Adhesive")
		(11 "B.Adhes" user "B.Adhesive")
		(13 "F.Paste" user "Package Geometry/Pastemask Top")
		(15 "B.Paste" user "Package Geometry/Pastemask Bottom")
		(5 "F.SilkS" user "Ref Des/Silkscreen Top")
		(7 "B.SilkS" user "Ref Des/Silkscreen Bottom")
		(1 "F.Mask" user "Board Geometry/Soldermask Top")
		(3 "B.Mask" user "Board Geometry/Soldermask Bottom")
		(17 "Dwgs.User" user "User.Drawings")
		(19 "Cmts.User" user "User.Comments")
		(21 "Eco1.User" user "User.Eco1")
		(23 "Eco2.User" user "User.Eco2")
		(25 "Edge.Cuts" user "Board Geometry/Outline")
		(27 "Margin" user)
		(31 "F.CrtYd" user "Package Geometry/Place Bound Top")
		(29 "B.CrtYd" user "Package Geometry/Place Bound Bottom")
		(35 "F.Fab" user "Ref Des/Assembly Top")
		(33 "B.Fab" user "Ref Des/Assembly Bottom")
	)
	(footprint ""
		(layer "B.Cu")
		(at 119.95912 -248.49836 -90)
		(property "Reference" "C447"
			(at 0 0 90)
			(layer "B.SilkS")
			(hide yes)
			(effects
				(font
					(size 1.27 1.27)
				)
				(justify mirror)
			)
		)
		(property "Value" ""
			(at 0 0 90)
			(layer "B.Fab")
			(effects
				(font
					(size 1.27 1.27)
				)
				(justify mirror)
			)
		)
		(duplicate_pad_numbers_are_jumpers no)
		(fp_line
			(start -1.524 0.762)
			(end 1.524 0.762)
			(stroke
				(width 0.1524)
				(type default)
			)
			(layer "B.SilkS")
		)
		(fp_line
			(start 1.524 0.762)
			(end 1.524 -0.762)
			(stroke
				(width 0.1524)
				(type default)
			)
			(layer "B.SilkS")
		)
		(fp_line
			(start -1.524 -0.762)
			(end -1.524 0.762)
			(stroke
				(width 0.1524)
				(type default)
			)
			(layer "B.SilkS")
		)
		(fp_line
			(start 1.524 -0.762)
			(end -1.524 -0.762)
			(stroke
				(width 0.1524)
				(type default)
			)
			(layer "B.SilkS")
		)
		(fp_line
			(start -1.1049 0.724916)
			(end -1.1049 -0.724916)
			(stroke
				(width 0.1)
				(type default)
			)
			(layer "B.Fab")
		)
		(fp_line
			(start 1.1049 0.724916)
			(end -1.1049 0.724916)
			(stroke
				(width 0.1)
				(type default)
			)
			(layer "B.Fab")
		)
		(fp_line
			(start -1.1049 -0.724916)
			(end 1.1049 -0.724916)
			(stroke
				(width 0.1)
				(type default)
			)
			(layer "B.Fab")
		)
		(fp_line
			(start 1.1049 -0.724916)
			(end 1.1049 0.724916)
			(stroke
				(width 0.1)
				(type default)
			)
			(layer "B.Fab")
		)
		(pad "1" smd rect
			(at 0.889 0 270)
			(size 1.016 1.27)
			(layers "B.Cu" "B.Mask" "B.Paste")
			(net "PVCCD_HV_CPU1")
		)
		(pad "2" smd rect
			(at -0.889 0 270)
			(size 1.016 1.27)
			(layers "B.Cu" "B.Mask" "B.Paste")
			(net "GND")
		)
	)
	(footprint ""
		(layer "B.Cu")
		(at 180.848 -18.710148 90)
		(property "Reference" "R2420"
			(at 0 0 90)
			(layer "B.SilkS")
			(hide yes)
			(effects
				(font
					(size 1.27 1.27)
				)
				(justify mirror)
			)
		)
		(property "Value" ""
			(at 0 0 90)
			(layer "B.Fab")
			(effects
				(font
					(size 1.27 1.27)
				)
				(justify mirror)
			)
		)
		(duplicate_pad_numbers_are_jumpers no)
		(fp_line
			(start 0.7874 -0.4064)
			(end -0.7874 -0.4064)
			(stroke
				(width 0.1524)
				(type default)
			)
			(layer "B.SilkS")
		)
		(fp_line
			(start -0.7874 -0.4064)
			(end -0.7874 0.4064)
			(stroke
				(width 0.1524)
				(type default)
			)
			(layer "B.SilkS")
		)
		(fp_line
			(start 0.7874 0.4064)
			(end 0.7874 -0.4064)
			(stroke
				(width 0.1524)
				(type default)
			)
			(layer "B.SilkS")
		)
		(fp_line
			(start -0.7874 0.4064)
			(end 0.7874 0.4064)
			(stroke
				(width 0.1524)
				(type default)
			)
			(layer "B.SilkS")
		)
		(fp_line
			(start 0.67945 -0.305054)
			(end 0.12065 -0.305054)
			(stroke
				(width 0.1)
				(type default)
			)
			(layer "B.Fab")
		)
		(fp_line
			(start 0.12065 -0.305054)
			(end 0.12065 -0.2794)
			(stroke
				(width 0.1)
				(type default)
			)
			(layer "B.Fab")
		)
		(fp_line
			(start -0.12065 -0.3048)
			(end -0.67945 -0.3048)
			(stroke
				(width 0.1)
				(type default)
			)
			(layer "B.Fab")
		)
		(fp_line
			(start -0.67945 -0.3048)
			(end -0.67945 0.3048)
			(stroke
				(width 0.1)
				(type default)
			)
			(layer "B.Fab")
		)
		(fp_line
			(start 0.12065 -0.2794)
			(end -0.12065 -0.2794)
			(stroke
				(width 0.1)
				(type default)
			)
			(layer "B.Fab")
		)
		(fp_line
			(start -0.12065 -0.2794)
			(end -0.12065 -0.3048)
			(stroke
				(width 0.1)
				(type default)
			)
			(layer "B.Fab")
		)
		(fp_line
			(start 0.12065 0.2794)
			(end 0.12065 0.3048)
			(stroke
				(width 0.1)
				(type default)
			)
			(layer "B.Fab")
		)
		(fp_line
			(start -0.120396 0.2794)
			(end 0.12065 0.2794)
			(stroke
				(width 0.1)
				(type default)
			)
			(layer "B.Fab")
		)
		(fp_line
			(start 0.67945 0.3048)
			(end 0.67945 -0.305054)
			(stroke
				(width 0.1)
				(type default)
			)
			(layer "B.Fab")
		)
		(fp_line
			(start 0.12065 0.3048)
			(end 0.67945 0.3048)
			(stroke
				(width 0.1)
				(type default)
			)
			(layer "B.Fab")
		)
		(fp_line
			(start -0.120396 0.3048)
			(end -0.120396 0.2794)
			(stroke
				(width 0.1)
				(type default)
			)
			(layer "B.Fab")
		)
		(fp_line
			(start -0.67945 0.3048)
			(end -0.120396 0.3048)
			(stroke
				(width 0.1)
				(type default)
			)
			(layer "B.Fab")
		)
		(pad "1" smd circle
			(at 0.40005 0 270)
			(size 0 0)
			(layers "B.Cu" "B.Mask" "B.Paste")
			(net "SMB_HOST_3V3AUX_SDA")
		)
		(pad "2" smd circle
			(at -0.40005 0 270)
			(size 0 0)
			(layers "B.Cu" "B.Mask" "B.Paste")
			(net "SMB_HOST_3V3AUX_SDA_R0")
		)
	)
	(footprint ""
		(layer "B.Cu")
		(at 364.342934 -255.853946 -90)
		(property "Reference" "C355"
			(at 0 0 90)
			(layer "B.SilkS")
			(hide yes)
			(effects
				(font
					(size 1.27 1.27)
				)
				(justify mirror)
			)
		)
		(property "Value" ""
			(at 0 0 90)
			(layer "B.Fab")
			(effects
				(font
					(size 1.27 1.27)
				)
				(justify mirror)
			)
		)
		(duplicate_pad_numbers_are_jumpers no)
		(fp_line
			(start -1.524 0.762)
			(end 1.524 0.762)
			(stroke
				(width 0.1524)
				(type default)
			)
			(layer "B.SilkS")
		)
		(fp_line
			(start 1.524 0.762)
			(end 1.524 -0.762)
			(stroke
				(width 0.1524)
				(type default)
			)
			(layer "B.SilkS")
		)
		(fp_line
			(start -1.524 -0.762)
			(end -1.524 0.762)
			(stroke
				(width 0.1524)
				(type default)
			)
			(layer "B.SilkS")
		)
		(fp_line
			(start 1.524 -0.762)
			(end -1.524 -0.762)
			(stroke
				(width 0.1524)
				(type default)
			)
			(layer "B.SilkS")
		)
		(fp_line
			(start -1.1049 0.724916)
			(end -1.1049 -0.724916)
			(stroke
				(width 0.1)
				(type default)
			)
			(layer "B.Fab")
		)
		(fp_line
			(start 1.1049 0.724916)
			(end -1.1049 0.724916)
			(stroke
				(width 0.1)
				(type default)
			)
			(layer "B.Fab")
		)
		(fp_line
			(start -1.1049 -0.724916)
			(end 1.1049 -0.724916)
			(stroke
				(width 0.1)
				(type default)
			)
			(layer "B.Fab")
		)
		(fp_line
			(start 1.1049 -0.724916)
			(end 1.1049 0.724916)
			(stroke
				(width 0.1)
				(type default)
			)
			(layer "B.Fab")
		)
		(pad "1" smd rect
			(at 0.889 0 270)
			(size 1.016 1.27)
			(layers "B.Cu" "B.Mask" "B.Paste")
			(net "PVCCIN_CPU0")
		)
		(pad "2" smd rect
			(at -0.889 0 270)
			(size 1.016 1.27)
			(layers "B.Cu" "B.Mask" "B.Paste")
			(net "GND")
		)
	)
)
